(kicad_pcb
	(version 20260206)
	(generator "pcbnew")
	(generator_version "10.0")
	(general
		(thickness 1.6)
		(legacy_teardrops no)
	)
	(paper "A4")
	(title_block
		(title "Bryce Canyon_IOM_M2_16342-2_OCP.brd")
		(comment 1 "Bryce Canyon / footprint 577 of 1146 (CN1), pads 75-148 of 202")
	)
	(layers
		(0 "F.Cu" signal "TOP")
		(4 "In1.Cu" signal "L2GND")
		(6 "In2.Cu" signal "L3")
		(8 "In3.Cu" signal "L4VCC")
		(10 "In4.Cu" signal "L5VCC")
		(12 "In5.Cu" signal "L6")
		(14 "In6.Cu" signal "L7GND")
		(2 "B.Cu" signal "BOTTOM")
		(9 "F.Adhes" user "F.Adhesive")
		(11 "B.Adhes" user "B.Adhesive")
		(13 "F.Paste" user "Package Geometry/Pastemask Top")
		(15 "B.Paste" user "Package Geometry/Pastemask Bottom")
		(5 "F.SilkS" user "Ref Des/Silkscreen Top")
		(7 "B.SilkS" user "Ref Des/Silkscreen Bottom")
		(1 "F.Mask" user "Board Geometry/Soldermask Top")
		(3 "B.Mask" user "Board Geometry/Soldermask Bottom")
		(17 "Dwgs.User" user "User.Drawings")
		(19 "Cmts.User" user "User.Comments")
		(21 "Eco1.User" user "User.Eco1")
		(23 "Eco2.User" user "User.Eco2")
		(25 "Edge.Cuts" user "Board Geometry/Outline")
		(27 "Margin" user)
		(31 "F.CrtYd" user "Package Geometry/Place Bound Top")
		(29 "B.CrtYd" user "Package Geometry/Place Bound Bottom")
		(35 "F.Fab" user "Ref Des/Assembly Top")
		(33 "B.Fab" user "Ref Des/Assembly Bottom")
	)
	(footprint ""
		(layer "F.Cu")
		(at 141.299946 -44.200064 180)
		(property "Reference" "CN1"
			(at 0 0 180)
			(layer "F.SilkS")
			(hide yes)
			(effects
				(font
					(size 1.27 1.27)
				)
			)
		)
		(property "Value" "AMP-CONN200-13R-4-GP"
			(at 30.332934 43.515534 180)
			(unlocked yes)
			(layer "F.Fab")
			(hide yes)
			(effects
				(font
					(size 1.016 1.016)
					(thickness 0.1524)
				)
			)
		)
		(property "Device Type" "PREFIT-200P-360520-1H542"
			(at 30.332934 41.991534 180)
			(unlocked yes)
			(layer "F.Fab")
			(hide yes)
			(effects
				(font
					(size 1.016 1.016)
					(thickness 0.1524)
				)
			)
		)
		(duplicate_pad_numbers_are_jumpers no)
		(pad "E9" thru_hole circle
			(at 21.599906 -7.199884 180)
			(size 0.762 0.762)
			(drill 0.359918)
			(layers "*.Cu" "*.Mask")
			(remove_unused_layers no)
			(net "PCIE_IOM_TO_COMP_16_DN")
			(clearance 0.1651)
			(thermal_gap 0.1651)
		)
		(pad "E10" thru_hole circle
			(at 23.400004 -5.999988 180)
			(size 0.762 0.762)
			(drill 0.359918)
			(layers "*.Cu" "*.Mask")
			(remove_unused_layers no)
			(net "PCIE_IOM_TO_COMP_17_DN")
			(clearance 0.1651)
			(thermal_gap 0.1651)
		)
		(pad "E11" thru_hole circle
			(at 25.200102 -7.199884 180)
			(size 0.762 0.762)
			(drill 0.359918)
			(layers "*.Cu" "*.Mask")
			(remove_unused_layers no)
			(net "PCIE_IOM_TO_COMP_18_DN")
			(clearance 0.1651)
			(thermal_gap 0.1651)
		)
		(pad "E12" thru_hole circle
			(at 26.999946 -5.999988 180)
			(size 0.762 0.762)
			(drill 0.359918)
			(layers "*.Cu" "*.Mask")
			(remove_unused_layers no)
			(net "PCIE_IOM_TO_COMP_19_DN")
			(clearance 0.1651)
			(thermal_gap 0.1651)
		)
		(pad "E13" thru_hole circle
			(at 28.800044 -7.199884 180)
			(size 0.762 0.762)
			(drill 0.359918)
			(layers "*.Cu" "*.Mask")
			(remove_unused_layers no)
			(net "PCIE_IOM_TO_COMP_20_DN")
			(clearance 0.1651)
			(thermal_gap 0.1651)
		)
		(pad "E14" thru_hole circle
			(at 30.599888 -5.999988 180)
			(size 0.762 0.762)
			(drill 0.359918)
			(layers "*.Cu" "*.Mask")
			(remove_unused_layers no)
			(net "PCIE_IOM_TO_COMP_21_DN")
			(clearance 0.1651)
			(thermal_gap 0.1651)
		)
		(pad "E15" thru_hole circle
			(at 32.399986 -7.199884 180)
			(size 0.762 0.762)
			(drill 0.359918)
			(layers "*.Cu" "*.Mask")
			(remove_unused_layers no)
			(net "PCIE_IOM_TO_COMP_22_DN")
			(clearance 0.1651)
			(thermal_gap 0.1651)
		)
		(pad "E16" thru_hole circle
			(at 34.200084 -5.999988 180)
			(size 0.762 0.762)
			(drill 0.359918)
			(layers "*.Cu" "*.Mask")
			(remove_unused_layers no)
			(net "PCIE_IOM_TO_COMP_23_DN")
			(clearance 0.1651)
			(thermal_gap 0.1651)
		)
		(pad "F1" thru_hole circle
			(at 0 -8.599932 180)
			(size 0.762 0.762)
			(drill 0.359918)
			(layers "*.Cu" "*.Mask")
			(remove_unused_layers no)
			(net "PCIE_IOM_TO_COMP_8_DP")
			(clearance 0.1651)
			(thermal_gap 0.1651)
		)
		(pad "F2" thru_hole circle
			(at 1.800098 -7.400036 180)
			(size 0.762 0.762)
			(drill 0.359918)
			(layers "*.Cu" "*.Mask")
			(remove_unused_layers no)
			(net "PCIE_IOM_TO_COMP_9_DP")
			(clearance 0.1651)
			(thermal_gap 0.1651)
		)
		(pad "F3" thru_hole circle
			(at 3.599942 -8.599932 180)
			(size 0.762 0.762)
			(drill 0.359918)
			(layers "*.Cu" "*.Mask")
			(remove_unused_layers no)
			(net "PCIE_IOM_TO_COMP_10_DP")
			(clearance 0.1651)
			(thermal_gap 0.1651)
		)
		(pad "F4" thru_hole circle
			(at 5.40004 -7.400036 180)
			(size 0.762 0.762)
			(drill 0.359918)
			(layers "*.Cu" "*.Mask")
			(remove_unused_layers no)
			(net "PCIE_IOM_TO_COMP_11_DP")
			(clearance 0.1651)
			(thermal_gap 0.1651)
		)
		(pad "F5" thru_hole circle
			(at 7.199884 -8.599932 180)
			(size 0.762 0.762)
			(drill 0.359918)
			(layers "*.Cu" "*.Mask")
			(remove_unused_layers no)
			(net "PCIE_IOM_TO_COMP_12_DP")
			(clearance 0.1651)
			(thermal_gap 0.1651)
		)
		(pad "F6" thru_hole circle
			(at 8.999982 -7.400036 180)
			(size 0.762 0.762)
			(drill 0.359918)
			(layers "*.Cu" "*.Mask")
			(remove_unused_layers no)
			(net "PCIE_IOM_TO_COMP_13_DP")
			(clearance 0.1651)
			(thermal_gap 0.1651)
		)
		(pad "F7" thru_hole circle
			(at 10.80008 -8.599932 180)
			(size 0.762 0.762)
			(drill 0.359918)
			(layers "*.Cu" "*.Mask")
			(remove_unused_layers no)
			(net "PCIE_IOM_TO_COMP_14_DP")
			(clearance 0.1651)
			(thermal_gap 0.1651)
		)
		(pad "F8" thru_hole circle
			(at 12.599924 -7.400036 180)
			(size 0.762 0.762)
			(drill 0.359918)
			(layers "*.Cu" "*.Mask")
			(remove_unused_layers no)
			(net "PCIE_IOM_TO_COMP_15_DP")
			(clearance 0.1651)
			(thermal_gap 0.1651)
		)
		(pad "F9" thru_hole circle
			(at 21.599906 -8.599932 180)
			(size 0.762 0.762)
			(drill 0.359918)
			(layers "*.Cu" "*.Mask")
			(remove_unused_layers no)
			(net "PCIE_IOM_TO_COMP_16_DP")
			(clearance 0.1651)
			(thermal_gap 0.1651)
		)
		(pad "F10" thru_hole circle
			(at 23.400004 -7.400036 180)
			(size 0.762 0.762)
			(drill 0.359918)
			(layers "*.Cu" "*.Mask")
			(remove_unused_layers no)
			(net "PCIE_IOM_TO_COMP_17_DP")
			(clearance 0.1651)
			(thermal_gap 0.1651)
		)
		(pad "F11" thru_hole circle
			(at 25.200102 -8.599932 180)
			(size 0.762 0.762)
			(drill 0.359918)
			(layers "*.Cu" "*.Mask")
			(remove_unused_layers no)
			(net "PCIE_IOM_TO_COMP_18_DP")
			(clearance 0.1651)
			(thermal_gap 0.1651)
		)
		(pad "F12" thru_hole circle
			(at 26.999946 -7.400036 180)
			(size 0.762 0.762)
			(drill 0.359918)
			(layers "*.Cu" "*.Mask")
			(remove_unused_layers no)
			(net "PCIE_IOM_TO_COMP_19_DP")
			(clearance 0.1651)
			(thermal_gap 0.1651)
		)
		(pad "F13" thru_hole circle
			(at 28.800044 -8.599932 180)
			(size 0.762 0.762)
			(drill 0.359918)
			(layers "*.Cu" "*.Mask")
			(remove_unused_layers no)
			(net "PCIE_IOM_TO_COMP_20_DP")
			(clearance 0.1651)
			(thermal_gap 0.1651)
		)
		(pad "F14" thru_hole circle
			(at 30.599888 -7.400036 180)
			(size 0.762 0.762)
			(drill 0.359918)
			(layers "*.Cu" "*.Mask")
			(remove_unused_layers no)
			(net "PCIE_IOM_TO_COMP_21_DP")
			(clearance 0.1651)
			(thermal_gap 0.1651)
		)
		(pad "F15" thru_hole circle
			(at 32.399986 -8.599932 180)
			(size 0.762 0.762)
			(drill 0.359918)
			(layers "*.Cu" "*.Mask")
			(remove_unused_layers no)
			(net "PCIE_IOM_TO_COMP_22_DP")
			(clearance 0.1651)
			(thermal_gap 0.1651)
		)
		(pad "F16" thru_hole circle
			(at 34.200084 -7.400036 180)
			(size 0.762 0.762)
			(drill 0.359918)
			(layers "*.Cu" "*.Mask")
			(remove_unused_layers no)
			(net "PCIE_IOM_TO_COMP_23_DP")
			(clearance 0.1651)
			(thermal_gap 0.1651)
		)
		(pad "G1" thru_hole circle
			(at 0 -10.80008 180)
			(size 0.762 0.762)
			(drill 0.359918)
			(layers "*.Cu" "*.Mask")
			(remove_unused_layers no)
			(net "PCIE_COMP_TO_IOM_8_DN")
			(clearance 0.1651)
			(thermal_gap 0.1651)
		)
		(pad "G2" thru_hole circle
			(at 1.800098 -9.59993 180)
			(size 0.762 0.762)
			(drill 0.359918)
			(layers "*.Cu" "*.Mask")
			(remove_unused_layers no)
			(net "PCIE_COMP_TO_IOM_9_DN")
			(clearance 0.1651)
			(thermal_gap 0.1651)
		)
		(pad "G3" thru_hole circle
			(at 3.599942 -10.80008 180)
			(size 0.762 0.762)
			(drill 0.359918)
			(layers "*.Cu" "*.Mask")
			(remove_unused_layers no)
			(net "PCIE_COMP_TO_IOM_10_DN")
			(clearance 0.1651)
			(thermal_gap 0.1651)
		)
		(pad "G4" thru_hole circle
			(at 5.40004 -9.59993 180)
			(size 0.762 0.762)
			(drill 0.359918)
			(layers "*.Cu" "*.Mask")
			(remove_unused_layers no)
			(net "PCIE_COMP_TO_IOM_11_DN")
			(clearance 0.1651)
			(thermal_gap 0.1651)
		)
		(pad "G5" thru_hole circle
			(at 7.199884 -10.80008 180)
			(size 0.762 0.762)
			(drill 0.359918)
			(layers "*.Cu" "*.Mask")
			(remove_unused_layers no)
			(net "PCIE_COMP_TO_IOM_12_DN")
			(clearance 0.1651)
			(thermal_gap 0.1651)
		)
		(pad "G6" thru_hole circle
			(at 8.999982 -9.59993 180)
			(size 0.762 0.762)
			(drill 0.359918)
			(layers "*.Cu" "*.Mask")
			(remove_unused_layers no)
			(net "PCIE_COMP_TO_IOM_13_DN")
			(clearance 0.1651)
			(thermal_gap 0.1651)
		)
		(pad "G7" thru_hole circle
			(at 10.80008 -10.80008 180)
			(size 0.762 0.762)
			(drill 0.359918)
			(layers "*.Cu" "*.Mask")
			(remove_unused_layers no)
			(net "PCIE_COMP_TO_IOM_14_DN")
			(clearance 0.1651)
			(thermal_gap 0.1651)
		)
		(pad "G8" thru_hole circle
			(at 12.599924 -9.59993 180)
			(size 0.762 0.762)
			(drill 0.359918)
			(layers "*.Cu" "*.Mask")
			(remove_unused_layers no)
			(net "PCIE_COMP_TO_IOM_15_DN")
			(clearance 0.1651)
			(thermal_gap 0.1651)
		)
		(pad "G9" thru_hole circle
			(at 21.599906 -10.80008 180)
			(size 0.762 0.762)
			(drill 0.359918)
			(layers "*.Cu" "*.Mask")
			(remove_unused_layers no)
			(net "PCIE_COMP_TO_IOM_16_DN")
			(clearance 0.1651)
			(thermal_gap 0.1651)
		)
		(pad "G10" thru_hole circle
			(at 23.400004 -9.59993 180)
			(size 0.762 0.762)
			(drill 0.359918)
			(layers "*.Cu" "*.Mask")
			(remove_unused_layers no)
			(net "PCIE_COMP_TO_IOM_17_DN")
			(clearance 0.1651)
			(thermal_gap 0.1651)
		)
		(pad "G11" thru_hole circle
			(at 25.200102 -10.80008 180)
			(size 0.762 0.762)
			(drill 0.359918)
			(layers "*.Cu" "*.Mask")
			(remove_unused_layers no)
			(net "PCIE_COMP_TO_IOM_18_DN")
			(clearance 0.1651)
			(thermal_gap 0.1651)
		)
		(pad "G12" thru_hole circle
			(at 26.999946 -9.59993 180)
			(size 0.762 0.762)
			(drill 0.359918)
			(layers "*.Cu" "*.Mask")
			(remove_unused_layers no)
			(net "PCIE_COMP_TO_IOM_19_DN")
			(clearance 0.1651)
			(thermal_gap 0.1651)
		)
		(pad "G13" thru_hole circle
			(at 28.800044 -10.80008 180)
			(size 0.762 0.762)
			(drill 0.359918)
			(layers "*.Cu" "*.Mask")
			(remove_unused_layers no)
			(net "PCIE_COMP_TO_IOM_20_DN")
			(clearance 0.1651)
			(thermal_gap 0.1651)
		)
		(pad "G14" thru_hole circle
			(at 30.599888 -9.59993 180)
			(size 0.762 0.762)
			(drill 0.359918)
			(layers "*.Cu" "*.Mask")
			(remove_unused_layers no)
			(net "PCIE_COMP_TO_IOM_21_DN")
			(clearance 0.1651)
			(thermal_gap 0.1651)
		)
		(pad "G15" thru_hole circle
			(at 32.399986 -10.80008 180)
			(size 0.762 0.762)
			(drill 0.359918)
			(layers "*.Cu" "*.Mask")
			(remove_unused_layers no)
			(net "PCIE_COMP_TO_IOM_22_DN")
			(clearance 0.1651)
			(thermal_gap 0.1651)
		)
		(pad "G16" thru_hole circle
			(at 34.200084 -9.59993 180)
			(size 0.762 0.762)
			(drill 0.359918)
			(layers "*.Cu" "*.Mask")
			(remove_unused_layers no)
			(net "PCIE_COMP_TO_IOM_23_DN")
			(clearance 0.1651)
			(thermal_gap 0.1651)
		)
		(pad "GND1" thru_hole circle
			(at 0 -2.500122 180)
			(size 0.762 0.762)
			(drill 0.359918)
			(layers "*.Cu" "*.Mask")
			(remove_unused_layers no)
			(net "GND")
			(clearance 0.1651)
			(thermal_gap 0.1651)
		)
		(pad "GND2" thru_hole circle
			(at 0 -6.100064 180)
			(size 0.762 0.762)
			(drill 0.359918)
			(layers "*.Cu" "*.Mask")
			(remove_unused_layers no)
			(net "GND")
			(clearance 0.1651)
			(thermal_gap 0.1651)
		)
		(pad "GND3" thru_hole circle
			(at 0 -9.700006 180)
			(size 0.762 0.762)
			(drill 0.359918)
			(layers "*.Cu" "*.Mask")
			(remove_unused_layers no)
			(net "GND")
			(clearance 0.1651)
			(thermal_gap 0.1651)
		)
		(pad "GND4" thru_hole circle
			(at 0 -13.299948 180)
			(size 0.762 0.762)
			(drill 0.359918)
			(layers "*.Cu" "*.Mask")
			(remove_unused_layers no)
			(net "GND")
			(clearance 0.1651)
			(thermal_gap 0.1651)
		)
		(pad "GND5" thru_hole circle
			(at 1.800098 2.29997 180)
			(size 0.762 0.762)
			(drill 0.359918)
			(layers "*.Cu" "*.Mask")
			(remove_unused_layers no)
			(net "GND")
			(clearance 0.1651)
			(thermal_gap 0.1651)
		)
		(pad "GND6" thru_hole circle
			(at 1.800098 -1.299972 180)
			(size 0.762 0.762)
			(drill 0.359918)
			(layers "*.Cu" "*.Mask")
			(remove_unused_layers no)
			(net "GND")
			(clearance 0.1651)
			(thermal_gap 0.1651)
		)
		(pad "GND7" thru_hole circle
			(at 1.800098 -4.899914 180)
			(size 0.762 0.762)
			(drill 0.359918)
			(layers "*.Cu" "*.Mask")
			(remove_unused_layers no)
			(net "GND")
			(clearance 0.1651)
			(thermal_gap 0.1651)
		)
		(pad "GND8" thru_hole circle
			(at 1.800098 -8.50011 180)
			(size 0.762 0.762)
			(drill 0.359918)
			(layers "*.Cu" "*.Mask")
			(remove_unused_layers no)
			(net "GND")
			(clearance 0.1651)
			(thermal_gap 0.1651)
		)
		(pad "GND9" thru_hole circle
			(at 1.800098 -12.100052 180)
			(size 0.762 0.762)
			(drill 0.359918)
			(layers "*.Cu" "*.Mask")
			(remove_unused_layers no)
			(net "GND")
			(clearance 0.1651)
			(thermal_gap 0.1651)
		)
		(pad "GND10" thru_hole circle
			(at 3.599942 -2.500122 180)
			(size 0.762 0.762)
			(drill 0.359918)
			(layers "*.Cu" "*.Mask")
			(remove_unused_layers no)
			(net "GND")
			(clearance 0.1651)
			(thermal_gap 0.1651)
		)
		(pad "GND11" thru_hole circle
			(at 3.599942 -6.100064 180)
			(size 0.762 0.762)
			(drill 0.359918)
			(layers "*.Cu" "*.Mask")
			(remove_unused_layers no)
			(net "GND")
			(clearance 0.1651)
			(thermal_gap 0.1651)
		)
		(pad "GND12" thru_hole circle
			(at 3.599942 -9.700006 180)
			(size 0.762 0.762)
			(drill 0.359918)
			(layers "*.Cu" "*.Mask")
			(remove_unused_layers no)
			(net "GND")
			(clearance 0.1651)
			(thermal_gap 0.1651)
		)
		(pad "GND13" thru_hole circle
			(at 3.599942 -13.299948 180)
			(size 0.762 0.762)
			(drill 0.359918)
			(layers "*.Cu" "*.Mask")
			(remove_unused_layers no)
			(net "GND")
			(clearance 0.1651)
			(thermal_gap 0.1651)
		)
		(pad "GND14" thru_hole circle
			(at 5.40004 2.29997 180)
			(size 0.762 0.762)
			(drill 0.359918)
			(layers "*.Cu" "*.Mask")
			(remove_unused_layers no)
			(net "GND")
			(clearance 0.1651)
			(thermal_gap 0.1651)
		)
		(pad "GND15" thru_hole circle
			(at 5.40004 -1.299972 180)
			(size 0.762 0.762)
			(drill 0.359918)
			(layers "*.Cu" "*.Mask")
			(remove_unused_layers no)
			(net "GND")
			(clearance 0.1651)
			(thermal_gap 0.1651)
		)
		(pad "GND16" thru_hole circle
			(at 5.40004 -4.899914 180)
			(size 0.762 0.762)
			(drill 0.359918)
			(layers "*.Cu" "*.Mask")
			(remove_unused_layers no)
			(net "GND")
			(clearance 0.1651)
			(thermal_gap 0.1651)
		)
		(pad "GND17" thru_hole circle
			(at 5.40004 -8.50011 180)
			(size 0.762 0.762)
			(drill 0.359918)
			(layers "*.Cu" "*.Mask")
			(remove_unused_layers no)
			(net "GND")
			(clearance 0.1651)
			(thermal_gap 0.1651)
		)
		(pad "GND18" thru_hole circle
			(at 5.40004 -12.100052 180)
			(size 0.762 0.762)
			(drill 0.359918)
			(layers "*.Cu" "*.Mask")
			(remove_unused_layers no)
			(net "GND")
			(clearance 0.1651)
			(thermal_gap 0.1651)
		)
		(pad "GND19" thru_hole circle
			(at 7.199884 -2.500122 180)
			(size 0.762 0.762)
			(drill 0.359918)
			(layers "*.Cu" "*.Mask")
			(remove_unused_layers no)
			(net "GND")
			(clearance 0.1651)
			(thermal_gap 0.1651)
		)
		(pad "GND20" thru_hole circle
			(at 7.199884 -6.100064 180)
			(size 0.762 0.762)
			(drill 0.359918)
			(layers "*.Cu" "*.Mask")
			(remove_unused_layers no)
			(net "GND")
			(clearance 0.1651)
			(thermal_gap 0.1651)
		)
		(pad "GND21" thru_hole circle
			(at 7.199884 -9.700006 180)
			(size 0.762 0.762)
			(drill 0.359918)
			(layers "*.Cu" "*.Mask")
			(remove_unused_layers no)
			(net "GND")
			(clearance 0.1651)
			(thermal_gap 0.1651)
		)
		(pad "GND22" thru_hole circle
			(at 7.199884 -13.299948 180)
			(size 0.762 0.762)
			(drill 0.359918)
			(layers "*.Cu" "*.Mask")
			(remove_unused_layers no)
			(net "GND")
			(clearance 0.1651)
			(thermal_gap 0.1651)
		)
		(pad "GND23" thru_hole circle
			(at 8.999982 2.29997 180)
			(size 0.762 0.762)
			(drill 0.359918)
			(layers "*.Cu" "*.Mask")
			(remove_unused_layers no)
			(net "GND")
			(clearance 0.1651)
			(thermal_gap 0.1651)
		)
		(pad "GND24" thru_hole circle
			(at 8.999982 -1.299972 180)
			(size 0.762 0.762)
			(drill 0.359918)
			(layers "*.Cu" "*.Mask")
			(remove_unused_layers no)
			(net "GND")
			(clearance 0.1651)
			(thermal_gap 0.1651)
		)
		(pad "GND25" thru_hole circle
			(at 8.999982 -4.899914 180)
			(size 0.762 0.762)
			(drill 0.359918)
			(layers "*.Cu" "*.Mask")
			(remove_unused_layers no)
			(net "GND")
			(clearance 0.1651)
			(thermal_gap 0.1651)
		)
		(pad "GND26" thru_hole circle
			(at 8.999982 -8.50011 180)
			(size 0.762 0.762)
			(drill 0.359918)
			(layers "*.Cu" "*.Mask")
			(remove_unused_layers no)
			(net "GND")
			(clearance 0.1651)
			(thermal_gap 0.1651)
		)
		(pad "GND27" thru_hole circle
			(at 8.999982 -12.100052 180)
			(size 0.762 0.762)
			(drill 0.359918)
			(layers "*.Cu" "*.Mask")
			(remove_unused_layers no)
			(net "GND")
			(clearance 0.1651)
			(thermal_gap 0.1651)
		)
		(pad "GND28" thru_hole circle
			(at 10.80008 -2.500122 180)
			(size 0.762 0.762)
			(drill 0.359918)
			(layers "*.Cu" "*.Mask")
			(remove_unused_layers no)
			(net "GND")
			(clearance 0.1651)
			(thermal_gap 0.1651)
		)
		(pad "GND29" thru_hole circle
			(at 10.80008 -6.100064 180)
			(size 0.762 0.762)
			(drill 0.359918)
			(layers "*.Cu" "*.Mask")
			(remove_unused_layers no)
			(net "GND")
			(clearance 0.1651)
			(thermal_gap 0.1651)
		)
		(pad "GND30" thru_hole circle
			(at 10.80008 -9.700006 180)
			(size 0.762 0.762)
			(drill 0.359918)
			(layers "*.Cu" "*.Mask")
			(remove_unused_layers no)
			(net "GND")
			(clearance 0.1651)
			(thermal_gap 0.1651)
		)
		(pad "GND31" thru_hole circle
			(at 10.80008 -13.299948 180)
			(size 0.762 0.762)
			(drill 0.359918)
			(layers "*.Cu" "*.Mask")
			(remove_unused_layers no)
			(net "GND")
			(clearance 0.1651)
			(thermal_gap 0.1651)
		)
		(pad "GND32" thru_hole circle
			(at 12.599924 2.29997 180)
			(size 0.762 0.762)
			(drill 0.359918)
			(layers "*.Cu" "*.Mask")
			(remove_unused_layers no)
			(net "GND")
			(clearance 0.1651)
			(thermal_gap 0.1651)
		)
		(pad "GND33" thru_hole circle
			(at 12.599924 -1.299972 180)
			(size 0.762 0.762)
			(drill 0.359918)
			(layers "*.Cu" "*.Mask")
			(remove_unused_layers no)
			(net "GND")
			(clearance 0.1651)
			(thermal_gap 0.1651)
		)
		(pad "GND34" thru_hole circle
			(at 12.599924 -4.899914 180)
			(size 0.762 0.762)
			(drill 0.359918)
			(layers "*.Cu" "*.Mask")
			(remove_unused_layers no)
			(net "GND")
			(clearance 0.1651)
			(thermal_gap 0.1651)
		)
	)
)
